#ISCELL
  mstr_symbols cad_note *
  *
#ISCELL
  mstr_symbols design_note *
  *
#ISCELL
  mstr_symbols intel_corp_bpage *
  *
#ISCELL
  mstr_standard offpage *
  page119_i10
#ISCELL
  mstr_standard offpage *
  page119_i101
#CELL
  mstr_u_proc lbg_core_qat_ext_d *
  page119_i115
#ISCELL
  mstr_standard offpage *
  page119_i119
#ISCELL
  mstr_standard tap *
  page119_i120
#ISCELL
  mstr_standard tap *
  page119_i121
#ISCELL
  mstr_standard tap *
  page119_i122
#ISCELL
  mstr_standard tap *
  page119_i123
#ISCELL
  mstr_standard offpage *
  page119_i124
#ISCELL
  mstr_standard offpage *
  page119_i125
#ISCELL
  mstr_standard offpage *
  page119_i127
#ISCELL
  mstr_standard offpage *
  page119_i128
#ISCELL
  mstr_standard offpage *
  page119_i129
#ISCELL
  mstr_standard offpage *
  page119_i13
#ISCELL
  mstr_standard offpage *
  page119_i130
#ISCELL
  mstr_standard offpage *
  page119_i131
#ISCELL
  mstr_standard offpage *
  page119_i132
#ISCELL
  mstr_standard offpage *
  page119_i136
#ISCELL
  mstr_standard offpage *
  page119_i137
#ISCELL
  mstr_standard offpage *
  page119_i139
#ISCELL
  mstr_standard offpage *
  page119_i14
#ISCELL
  mstr_standard offpage *
  page119_i140
#ISCELL
  mstr_standard offpage *
  page119_i141
#ISCELL
  mstr_standard offpage *
  page119_i142
#ISCELL
  mstr_standard offpage *
  page119_i143
#ISCELL
  mstr_standard offpage *
  page119_i144
#ISCELL
  mstr_standard offpage *
  page119_i145
#ISCELL
  mstr_standard offpage *
  page119_i146
#ISCELL
  mstr_standard offpage *
  page119_i148
#ISCELL
  mstr_standard offpage *
  page119_i150
#ISCELL
  mstr_standard offpage *
  page119_i151
#ISCELL
  mstr_standard offpage *
  page119_i154
#ISCELL
  mstr_standard offpage *
  page119_i155
#ISCELL
  mstr_standard offpage *
  page119_i156
#ISCELL
  mstr_standard offpage *
  page119_i158
#ISCELL
  mstr_standard offpage *
  page119_i159
#ISCELL
  mstr_standard offpage *
  page119_i161
#ISCELL
  mstr_standard offpage *
  page119_i164
#ISCELL
  mstr_standard offpage *
  page119_i166
#ISCELL
  mstr_standard offpage *
  page119_i170
#ISCELL
  mstr_standard offpage *
  page119_i171
#CELL
  mstr_discrete res *
  page119_i172
#CELL
  mstr_discrete res *
  page119_i173
#CELL
  mstr_discrete res *
  page119_i174
#CELL
  mstr_discrete fet_n_dual *
  page119_i175
#ISCELL
  mstr_standard offpage *
  page119_i176
#ISCELL
  mstr_symbols p3v3_stby *
  page119_i177
#CELL
  mstr_discrete res *
  page119_i178
#CELL
  mstr_discrete led *
  page119_i179
#CELL
  mstr_discrete fet_n_dual *
  page119_i180
#ISCELL
  mstr_symbols gnd *
  page119_i181
#ISCELL
  mstr_symbols p3v3_stby *
  page119_i182
#CELL
  mstr_discrete res *
  page119_i183
#ISCELL
  mstr_symbols gnd *
  page119_i184
#ISCELL
  mstr_symbols p3v3_stby *
  page119_i185
#CELL
  mstr_discrete res *
  page119_i186
#ISCELL
  mstr_standard offpage *
  page119_i187
#ISCELL
  mstr_standard offpage *
  page119_i188
#CELL
  mstr_discrete res *
  page119_i189
#ISCELL
  mstr_standard offpage *
  page119_i190
#ISCELL
  mstr_standard offpage *
  page119_i196
#ISCELL
  mstr_standard offpage *
  page119_i197
#ISCELL
  mstr_standard offpage *
  page119_i198
#ISCELL
  mstr_standard offpage *
  page119_i2
#ISCELL
  mstr_standard offpage *
  page119_i202
#ISCELL
  mstr_standard offpage *
  page119_i203
#ISCELL
  mstr_standard offpage *
  page119_i205
#ISCELL
  mstr_standard offpage *
  page119_i208
#ISCELL
  mstr_standard offpage *
  page119_i209
#ISCELL
  mstr_standard offpage *
  page119_i21
#ISCELL
  mstr_standard offpage *
  page119_i211
#ISCELL
  mstr_standard offpage *
  page119_i212
#CELL
  mstr_discrete res *
  page119_i213
#ISCELL
  mstr_symbols p3v3_stby *
  page119_i214
#ISCELL
  mstr_standard offpage *
  page119_i216
#ISCELL
  mstr_standard offpage *
  page119_i217
#ISCELL
  mstr_standard offpage *
  page119_i218
#ISCELL
  mstr_standard offpage *
  page119_i219
#ISCELL
  mstr_standard offpage *
  page119_i22
#ISCELL
  mstr_standard offpage *
  page119_i220
#ISCELL
  mstr_standard offpage *
  page119_i221
#ISCELL
  mstr_standard offpage *
  page119_i222
#CELL
  mstr_discrete res *
  page119_i223
#CELL
  mstr_discrete res *
  page119_i224
#CELL
  mstr_discrete res *
  page119_i226
#CELL
  mstr_discrete res *
  page119_i227
#CELL
  mstr_discrete res *
  page119_i228
#CELL
  mstr_discrete res *
  page119_i229
#ISCELL
  mstr_standard offpage *
  page119_i23
#CELL
  mstr_discrete res *
  page119_i230
#ISCELL
  mstr_symbols p3v3_stby *
  page119_i231
#ISCELL
  mstr_standard offpage *
  page119_i26
#ISCELL
  mstr_standard offpage *
  page119_i29
#ISCELL
  mstr_standard offpage *
  page119_i31
#ISCELL
  mstr_standard offpage *
  page119_i32
#ISCELL
  mstr_standard offpage *
  page119_i33
#ISCELL
  mstr_standard offpage *
  page119_i34
#ISCELL
  mstr_standard offpage *
  page119_i35
#ISCELL
  mstr_standard offpage *
  page119_i37
#ISCELL
  mstr_standard offpage *
  page119_i39
#ISCELL
  mstr_standard offpage *
  page119_i40
#ISCELL
  mstr_standard offpage *
  page119_i42
#ISCELL
  mstr_standard offpage *
  page119_i46
#ISCELL
  mstr_standard offpage *
  page119_i47
#ISCELL
  mstr_standard offpage *
  page119_i48
#ISCELL
  mstr_standard offpage *
  page119_i49
#ISCELL
  mstr_standard offpage *
  page119_i50
#ISCELL
  mstr_standard offpage *
  page119_i51
#ISCELL
  mstr_standard offpage *
  page119_i52
#ISCELL
  mstr_standard offpage *
  page119_i53
#ISCELL
  mstr_standard offpage *
  page119_i54
#ISCELL
  mstr_standard offpage *
  page119_i55
#ISCELL
  mstr_standard offpage *
  page119_i63
#ISCELL
  mstr_standard offpage *
  page119_i67
#ISCELL
  mstr_standard offpage *
  page119_i7
#ISCELL
  mstr_standard offpage *
  page119_i8
#ISCELL
  mstr_standard offpage *
  page119_i86
#ISCELL
  mstr_standard offpage *
  page119_i87
#ISCELL
  mstr_standard offpage *
  page119_i88
#ISCELL
  mstr_standard offpage *
  page119_i9
